# S9S_MB_2U (Grand Teton) — schematic netlist excerpt (pin names and nets, part order shuffled) for the footprints in the layout excerpt that follows; sources: Cadence DE-HDL packaged netlist, KiCad conversion of 03242023_DA0F0TMBIJ0_F0T_Motherboard_J_brd_V01_OCP.brd

C949  Q_CAP_DIFFBUS  DIFF BUS_0.22UF 6.3V 20% X6S  pkg C0201  page 173 : \1\ = P5E_CPU0_PE2_TX_C_DP<8> ; \2\ = P5E_CPU0_PE2_TX_DP<8>
R3658  Q_RES  10K 1% EMPTY  pkg 0402LF  page 152 : A = P3V3_AUX ; B = USB_HUB_OVCUR3
PR3843  Q_RES  49.9 1% CHIP  pkg 0603LF  page 157 : A = P12V_AUX ; B = P12V_OCP_AVIN_PD_1

(kicad_pcb
	(version 20260206)
	(generator "pcbnew")
	(generator_version "10.0")
	(general
		(thickness 1.6)
		(legacy_teardrops no)
	)
	(paper "A4")
	(title_block
		(title "03242023_DA0F0TMBIJ0_F0T_Motherboard_J_brd_V01_OCP.brd")
		(comment 1 "Grand Teton / footprints 937-939 of 6105")
	)
	(layers
		(0 "F.Cu" signal "TOP")
		(4 "In1.Cu" signal "GND")
		(6 "In2.Cu" signal "IN1")
		(8 "In3.Cu" signal "GND1")
		(10 "In4.Cu" signal "IN2")
		(12 "In5.Cu" signal "GND2")
		(14 "In6.Cu" signal "IN3")
		(16 "In7.Cu" signal "GND3")
		(18 "In8.Cu" signal "VCC")
		(20 "In9.Cu" signal "VCC1")
		(22 "In10.Cu" signal "GND4")
		(24 "In11.Cu" signal "IN4")
		(26 "In12.Cu" signal "GND5")
		(28 "In13.Cu" signal "IN5")
		(30 "In14.Cu" signal "GND6")
		(32 "In15.Cu" signal "IN6")
		(34 "In16.Cu" signal "GND7")
		(2 "B.Cu" signal "BOTTOM")
		(9 "F.Adhes" user "F.Adhesive")
		(11 "B.Adhes" user "B.Adhesive")
		(13 "F.Paste" user "Package Geometry/Pastemask Top")
		(15 "B.Paste" user "Package Geometry/Pastemask Bottom")
		(5 "F.SilkS" user "Ref Des/Silkscreen Top")
		(7 "B.SilkS" user "Ref Des/Silkscreen Bottom")
		(1 "F.Mask" user "Board Geometry/Soldermask Top")
		(3 "B.Mask" user "Board Geometry/Soldermask Bottom")
		(17 "Dwgs.User" user "User.Drawings")
		(19 "Cmts.User" user "User.Comments")
		(21 "Eco1.User" user "User.Eco1")
		(23 "Eco2.User" user "User.Eco2")
		(25 "Edge.Cuts" user "Board Geometry/Outline")
		(27 "Margin" user)
		(31 "F.CrtYd" user "Package Geometry/Place Bound Top")
		(29 "B.CrtYd" user "Package Geometry/Place Bound Bottom")
		(35 "F.Fab" user "Ref Des/Assembly Top")
		(33 "B.Fab" user "Ref Des/Assembly Bottom")
	)
	(footprint ""
		(layer "F.Cu")
		(at 16.110966 -92.687648 90)
		(property "Reference" "R3658"
			(at 0 0 90)
			(layer "F.SilkS")
			(hide yes)
			(effects
				(font
					(size 1.27 1.27)
				)
			)
		)
		(property "Value" ""
			(at 0 0 90)
			(layer "F.Fab")
			(effects
				(font
					(size 1.27 1.27)
				)
			)
		)
		(duplicate_pad_numbers_are_jumpers no)
		(fp_line
			(start 0.7874 -0.4064)
			(end 0.7874 0.4064)
			(stroke
				(width 0.1524)
				(type default)
			)
			(layer "F.SilkS")
		)
		(fp_line
			(start -0.7874 -0.4064)
			(end 0.7874 -0.4064)
			(stroke
				(width 0.1524)
				(type default)
			)
			(layer "F.SilkS")
		)
		(fp_line
			(start 0.7874 0.4064)
			(end -0.7874 0.4064)
			(stroke
				(width 0.1524)
				(type default)
			)
			(layer "F.SilkS")
		)
		(fp_line
			(start -0.7874 0.4064)
			(end -0.7874 -0.4064)
			(stroke
				(width 0.1524)
				(type default)
			)
			(layer "F.SilkS")
		)
		(fp_line
			(start -0.12065 -0.305054)
			(end -0.12065 -0.2794)
			(stroke
				(width 0.1)
				(type default)
			)
			(layer "F.Fab")
		)
		(fp_line
			(start -0.67945 -0.305054)
			(end -0.12065 -0.305054)
			(stroke
				(width 0.1)
				(type default)
			)
			(layer "F.Fab")
		)
		(fp_line
			(start 0.67945 -0.3048)
			(end 0.67945 0.3048)
			(stroke
				(width 0.1)
				(type default)
			)
			(layer "F.Fab")
		)
		(fp_line
			(start 0.12065 -0.3048)
			(end 0.67945 -0.3048)
			(stroke
				(width 0.1)
				(type default)
			)
			(layer "F.Fab")
		)
		(fp_line
			(start 0.12065 -0.2794)
			(end 0.12065 -0.3048)
			(stroke
				(width 0.1)
				(type default)
			)
			(layer "F.Fab")
		)
		(fp_line
			(start -0.12065 -0.2794)
			(end 0.12065 -0.2794)
			(stroke
				(width 0.1)
				(type default)
			)
			(layer "F.Fab")
		)
		(fp_line
			(start 0.120396 0.2794)
			(end -0.12065 0.2794)
			(stroke
				(width 0.1)
				(type default)
			)
			(layer "F.Fab")
		)
		(fp_line
			(start -0.12065 0.2794)
			(end -0.12065 0.3048)
			(stroke
				(width 0.1)
				(type default)
			)
			(layer "F.Fab")
		)
		(fp_line
			(start 0.67945 0.3048)
			(end 0.120396 0.3048)
			(stroke
				(width 0.1)
				(type default)
			)
			(layer "F.Fab")
		)
		(fp_line
			(start 0.120396 0.3048)
			(end 0.120396 0.2794)
			(stroke
				(width 0.1)
				(type default)
			)
			(layer "F.Fab")
		)
		(fp_line
			(start -0.12065 0.3048)
			(end -0.67945 0.3048)
			(stroke
				(width 0.1)
				(type default)
			)
			(layer "F.Fab")
		)
		(fp_line
			(start -0.67945 0.3048)
			(end -0.67945 -0.305054)
			(stroke
				(width 0.1)
				(type default)
			)
			(layer "F.Fab")
		)
		(pad "1" smd circle
			(at -0.40005 0 90)
			(size 0 0)
			(layers "F.Cu" "F.Mask" "F.Paste")
			(net "P3V3_AUX")
		)
		(pad "2" smd circle
			(at 0.40005 0 90)
			(size 0 0)
			(layers "F.Cu" "F.Mask" "F.Paste")
			(net "USB_HUB_OVCUR3")
		)
	)
	(footprint ""
		(layer "F.Cu")
		(at 392.84021 -402.371052 -90)
		(property "Reference" "C949"
			(at 0 0 270)
			(layer "F.SilkS")
			(hide yes)
			(effects
				(font
					(size 1.27 1.27)
				)
			)
		)
		(property "Value" ""
			(at 0 0 270)
			(layer "F.Fab")
			(effects
				(font
					(size 1.27 1.27)
				)
			)
		)
		(duplicate_pad_numbers_are_jumpers no)
		(fp_line
			(start -0.299974 0.150114)
			(end -0.299974 -0.150114)
			(stroke
				(width 0.1)
				(type default)
			)
			(layer "F.Fab")
		)
		(fp_line
			(start 0.299974 0.150114)
			(end -0.299974 0.150114)
			(stroke
				(width 0.1)
				(type default)
			)
			(layer "F.Fab")
		)
		(fp_line
			(start -0.299974 -0.150114)
			(end 0.299974 -0.150114)
			(stroke
				(width 0.1)
				(type default)
			)
			(layer "F.Fab")
		)
		(fp_line
			(start 0.299974 -0.150114)
			(end 0.299974 0.150114)
			(stroke
				(width 0.1)
				(type default)
			)
			(layer "F.Fab")
		)
		(pad "1" smd rect
			(at -0.2667 0 270)
			(size 0.3048 0.381)
			(layers "F.Cu" "F.Mask" "F.Paste")
			(net "P5E_CPU0_PE2_TX_C_DP<8>")
		)
		(pad "2" smd rect
			(at 0.2667 0 270)
			(size 0.3048 0.381)
			(layers "F.Cu" "F.Mask" "F.Paste")
			(net "P5E_CPU0_PE2_TX_DP<8>")
		)
	)
	(footprint ""
		(layer "F.Cu")
		(at 439.295032 -23.839678)
		(property "Reference" "PR3843"
			(at 0 0 0)
			(layer "F.SilkS")
			(hide yes)
			(effects
				(font
					(size 1.27 1.27)
				)
			)
		)
		(property "Value" ""
			(at 0 0 0)
			(layer "F.Fab")
			(effects
				(font
					(size 1.27 1.27)
				)
			)
		)
		(duplicate_pad_numbers_are_jumpers no)
		(fp_line
			(start -1.2954 -0.5842)
			(end 1.2954 -0.5842)
			(stroke
				(width 0.1524)
				(type default)
			)
			(layer "F.SilkS")
		)
		(fp_line
			(start -1.2954 0.5842)
			(end -1.2954 -0.5842)
			(stroke
				(width 0.1524)
				(type default)
			)
			(layer "F.SilkS")
		)
		(fp_line
			(start 1.2954 -0.5842)
			(end 1.2954 0.5842)
			(stroke
				(width 0.1524)
				(type default)
			)
			(layer "F.SilkS")
		)
		(fp_line
			(start 1.2954 0.5842)
			(end -1.2954 0.5842)
			(stroke
				(width 0.1524)
				(type default)
			)
			(layer "F.SilkS")
		)
		(fp_line
			(start -1.1938 -0.406654)
			(end -0.8636 -0.406654)
			(stroke
				(width 0.1)
				(type default)
			)
			(layer "F.Fab")
		)
		(fp_line
			(start -1.1938 0.4064)
			(end -1.1938 -0.406654)
			(stroke
				(width 0.1)
				(type default)
			)
			(layer "F.Fab")
		)
		(fp_line
			(start -0.8636 -0.4572)
			(end 0.8636 -0.4572)
			(stroke
				(width 0.1)
				(type default)
			)
			(layer "F.Fab")
		)
		(fp_line
			(start -0.8636 -0.406654)
			(end -0.8636 -0.4572)
			(stroke
				(width 0.1)
				(type default)
			)
			(layer "F.Fab")
		)
		(fp_line
			(start -0.8636 0.4064)
			(end -1.1938 0.4064)
			(stroke
				(width 0.1)
				(type default)
			)
			(layer "F.Fab")
		)
		(fp_line
			(start -0.8636 0.4318)
			(end -0.8636 0.4064)
			(stroke
				(width 0.1)
				(type default)
			)
			(layer "F.Fab")
		)
		(fp_line
			(start -0.8636 0.4572)
			(end -0.8636 0.4318)
			(stroke
				(width 0.1)
				(type default)
			)
			(layer "F.Fab")
		)
		(fp_line
			(start 0.8636 -0.4572)
			(end 0.8636 -0.406654)
			(stroke
				(width 0.1)
				(type default)
			)
			(layer "F.Fab")
		)
		(fp_line
			(start 0.8636 -0.406654)
			(end 1.1938 -0.406654)
			(stroke
				(width 0.1)
				(type default)
			)
			(layer "F.Fab")
		)
		(fp_line
			(start 0.8636 0.4064)
			(end 0.8636 0.4572)
			(stroke
				(width 0.1)
				(type default)
			)
			(layer "F.Fab")
		)
		(fp_line
			(start 0.8636 0.4572)
			(end -0.8636 0.4572)
			(stroke
				(width 0.1)
				(type default)
			)
			(layer "F.Fab")
		)
		(fp_line
			(start 1.1938 -0.406654)
			(end 1.1938 0.4064)
			(stroke
				(width 0.1)
				(type default)
			)
			(layer "F.Fab")
		)
		(fp_line
			(start 1.1938 0.4064)
			(end 0.8636 0.4064)
			(stroke
				(width 0.1)
				(type default)
			)
			(layer "F.Fab")
		)
		(pad "1" smd rect
			(at -0.7366 0 270)
			(size 0.7112 0.8128)
			(layers "F.Cu" "F.Mask" "F.Paste")
			(net "P12V_AUX")
		)
		(pad "2" smd rect
			(at 0.7366 0 270)
			(size 0.7112 0.8128)
			(layers "F.Cu" "F.Mask" "F.Paste")
			(net "P12V_OCP_AVIN_PD_1")
		)
	)
)
